FILE_TYPE = CONNECTIVITY;
{Allegro Design Entry HDL 17.4-2019 S026 (4007227) 1/17/2022}
"PAGE_NUMBER" = 422;
0"NC";
1"P0V9_CPU0_RT2_2A\g";
2"GND\g";
3"P1V8_CPU0_RT_1D\g";
4"GND\g";
5"P1V8_CPU0_RT2_1A\g";
6"GND\g";
7"P0V9_CPU0_RT_2D\g";
8"GND\g";
9"GND\g";
10"P1V8_CPU0_RT2_1A_1D\g";
11"P0V9_CPU0_RT2_2A_2D\g";
12"GND\g";
13"GND\g";
%"Q_CAP"
"1","(-6350,3375)","0","pure_quanta","I10";
;
LOCATION"C775"
$SEC"1"
CDS_SEC"1"
VOLTAGE"10V"
PACK_TYPE"C0201"
MATERIAL"X7S"
VALUE"0.1UF"
TOLERANCE"10%"
CDS_LIB"pure_quanta"
PART_NUMBER"CH4102K6E00";
"B"
$PN"2"13;
"A"
$PN"1"10;
%"P1V0"
"1","(-6750,3775)","0","pure_quanta_power","I11";
;
HDL_POWER"P1V8_CPU0_RT2_1A_1D"
CDS_LIB"pure_quanta_power";
"A"10;
%"Q_CAP"
"1","(-6625,4475)","0","pure_quanta","I12";
;
LOCATION"C671"
$SEC"1"
CDS_SEC"1"
VOLTAGE"6.3V"
TOLERANCE"20%"
MATERIAL"X6S"
PACK_TYPE"C0402"
VALUE"10UF"
CDS_LIB"pure_quanta"
PART_NUMBER"CH6101MEB01";
"B"
$PN"2"6;
"A"
$PN"1"5;
%"Q_CAP"
"1","(-6425,4475)","0","pure_quanta","I13";
;
LOCATION"C670"
$SEC"1"
CDS_SEC"1"
VOLTAGE"6.3V"
TOLERANCE"20%"
PACK_TYPE"0402"
MATERIAL"X6S"
VALUE"4.7UF"
CDS_LIB"pure_quanta"
PART_NUMBER"CH5471MEB01";
"B"
$PN"2"6;
"A"
$PN"1"5;
%"UNIVERSAL_GND"
"1","(-6000,4150)","0","pure_quanta_power","I14";
;
CDS_LIB"pure_quanta_power"
HDL_POWER"GND";
"A"6;
%"Q_CAP"
"1","(-6200,4475)","0","pure_quanta","I15";
;
LOCATION"C673"
$SEC"1"
CDS_SEC"1"
PACK_TYPE"0201"
MATERIAL"X6S"
VOLTAGE"4V"
TOLERANCE"20%"
VALUE"1UF"
CDS_LIB"pure_quanta"
PART_NUMBER"CH-10KMEE00";
"B"
$PN"2"6;
"A"
$PN"1"5;
%"Q_CAP"
"1","(-6000,4475)","0","pure_quanta","I16";
;
LOCATION"C677"
$SEC"1"
CDS_SEC"1"
VALUE"1UF"
TOLERANCE"20%"
VOLTAGE"4V"
MATERIAL"X6S"
PACK_TYPE"0201"
CDS_LIB"pure_quanta"
PART_NUMBER"CH-10KMEE00";
"B"
$PN"2"6;
"A"
$PN"1"5;
%"Q_CAP"
"1","(-5775,4475)","0","pure_quanta","I17";
;
LOCATION"C774"
$SEC"1"
CDS_SEC"1"
TOLERANCE"10%"
VALUE"0.1UF"
VOLTAGE"10V"
MATERIAL"X7S"
PACK_TYPE"C0201"
CDS_LIB"pure_quanta"
PART_NUMBER"CH4102K6E00";
"B"
$PN"2"6;
"A"
$PN"1"5;
%"Q_CAP"
"1","(-5525,4475)","0","pure_quanta","I18";
;
LOCATION"C776"
$SEC"1"
CDS_SEC"1"
PACK_TYPE"C0201"
MATERIAL"X7S"
VOLTAGE"10V"
VALUE"0.1UF"
TOLERANCE"10%"
CDS_LIB"pure_quanta"
PART_NUMBER"CH4102K6E00";
"B"
$PN"2"6;
"A"
$PN"1"5;
%"Q_CAP"
"1","(-5275,4475)","0","pure_quanta","I19";
;
LOCATION"C777"
$SEC"1"
CDS_SEC"1"
PACK_TYPE"C0201"
TOLERANCE"10%"
VALUE"0.1UF"
VOLTAGE"10V"
MATERIAL"X7S"
CDS_LIB"pure_quanta"
PART_NUMBER"CH4102K6E00";
"B"
$PN"2"6;
"A"
$PN"1"5;
%"Q_CAP"
"1","(-5000,4475)","0","pure_quanta","I20";
;
LOCATION"C778"
$SEC"1"
CDS_SEC"1"
TOLERANCE"10%"
VALUE"0.1UF"
PACK_TYPE"C0201"
MATERIAL"X7S"
VOLTAGE"10V"
CDS_LIB"pure_quanta"
PART_NUMBER"CH4102K6E00";
"B"
$PN"2"6;
"A"
$PN"1"5;
%"Q_RES"
"2","(-4150,3050)","2","pure_quanta","I21";
;
LOCATION"R1051"
$SEC"1"
CDS_SEC"1"
VALUE"0"
MATERIAL"EMPTY"
WATTAGE"1/4W"
TOLERANCE"5%"
PACK_TYPE"0603LF"
CDS_LIB"pure_quanta"
PART_NUMBER"CS00006J900";
"A"
$PN"1"7;
"B"
$PN"2"11;
%"Q_RES"
"1","(-3775,2775)","0","pure_quanta","I22";
;
LOCATION"R1053"
$SEC"1"
CDS_SEC"1"
WATTAGE"1/4W"
VALUE"0"
PACK_TYPE"0603LF"
TOLERANCE"5%"
MATERIAL"CHIP"
CDS_LIB"pure_quanta"
PART_NUMBER"CS00006J900";
"B"
$PN"2"1;
"A"
$PN"1"11;
%"Q_INDUCTOR"
"1","(-7625,4750)","0","pure_quanta","I23";
;
LOCATION"L18"
$SEC"1"
CDS_SEC"1"
MATERIAL"IND"
PACK_TYPE"SMLF"
VALUE"BLM21SN300SN1D/5A"
CDS_LIB"pure_quanta"
NEEDS_NO_SIZE"TRUE"
PART_NUMBER"CX300SN1000";
"1"
$PN"1"3;
"2"
$PN"2"5;
%"P1V0"
"1","(-7150,4950)","0","pure_quanta_power","I24";
;
HDL_POWER"P1V8_CPU0_RT2_1A"
CDS_LIB"pure_quanta_power";
"A"5;
%"Q_CAP"
"1","(-6900,5300)","0","pure_quanta","I25";
;
LOCATION"C665"
$SEC"1"
CDS_SEC"1"
VOLTAGE"4V"
MATERIAL"X6S"
TOLERANCE"20%"
VALUE"100UF"
PACK_TYPE"C0805"
CDS_LIB"pure_quanta"
PART_NUMBER"CH710KMEA01";
"B"
$PN"2"4;
"A"
$PN"1"3;
%"Q_CAP"
"1","(-6400,5275)","0","pure_quanta","I26";
;
LOCATION"C669"
$SEC"1"
CDS_SEC"1"
VALUE"10UF"
VOLTAGE"6.3V"
TOLERANCE"20%"
MATERIAL"X6S"
PACK_TYPE"C0402"
CDS_LIB"pure_quanta"
PART_NUMBER"CH6101MEB01";
"B"
$PN"2"4;
"A"
$PN"1"3;
%"Q_CAP"
"1","(-6650,5300)","0","pure_quanta","I27";
;
LOCATION"C667"
$SEC"1"
CDS_SEC"1"
VALUE"22UF"
VOLTAGE"4V"
TOLERANCE"20%"
MATERIAL"X6S"
PACK_TYPE"C0402"
CDS_LIB"pure_quanta"
PART_NUMBER"CH622KMEB02";
"B"
$PN"2"4;
"A"
$PN"1"3;
%"UNIVERSAL_GND"
"1","(-6225,5000)","0","pure_quanta_power","I28";
;
CDS_LIB"pure_quanta_power"
HDL_POWER"GND";
"A"4;
%"Q_CAP"
"1","(-6150,5275)","0","pure_quanta","I29";
;
LOCATION"C672"
$SEC"1"
CDS_SEC"1"
TOLERANCE"20%"
VOLTAGE"6.3V"
VALUE"4.7UF"
MATERIAL"X6S"
PACK_TYPE"0402"
CDS_LIB"pure_quanta"
PART_NUMBER"CH5471MEB01";
"B"
$PN"2"4;
"A"
$PN"1"3;
%"P1V0"
"1","(-8000,5575)","0","pure_quanta_power","I3";
;
HDL_POWER"P1V8_CPU0_RT_1D"
CDS_LIB"pure_quanta_power";
"A"3;
%"Q_INDUCTOR"
"1","(-3675,4750)","0","pure_quanta","I30";
;
LOCATION"L21"
$SEC"1"
CDS_SEC"1"
VALUE"100NH/16A"
PACK_TYPE"SMLF"
MATERIAL"IND"
NEEDS_NO_SIZE"TRUE"
CDS_LIB"pure_quanta"
PART_NUMBER"CV+10G0MZ04";
"1"
$PN"1"7;
"2"
$PN"2"1;
%"VCC_CORE"
"1","(-4150,6250)","0","pure_quanta_power","I31";
;
HDL_POWER"P0V9_CPU0_RT_2D"
CDS_LIB"pure_quanta_power";
"A"7;
%"VCC_CORE"
"1","(-3000,1950)","0","pure_quanta_power","I33";
;
HDL_POWER"P0V9_CPU0_RT2_2A_2D"
CDS_LIB"pure_quanta_power";
"A"11;
%"Q_CAP"
"1","(-3050,2525)","0","pure_quanta","I34";
;
LOCATION"C982"
$SEC"1"
CDS_SEC"1"
MATERIAL"X7S"
TOLERANCE"10%"
PACK_TYPE"C0201"
VOLTAGE"10V"
VALUE"0.1UF"
CDS_LIB"pure_quanta"
PART_NUMBER"CH4102K6E00";
"B"
$PN"2"9;
"A"
$PN"1"1;
%"Q_CAP"
"1","(-2750,2525)","0","pure_quanta","I35";
;
LOCATION"C984"
$SEC"1"
CDS_SEC"1"
VOLTAGE"10V"
VALUE"0.1UF"
PACK_TYPE"C0201"
MATERIAL"X7S"
TOLERANCE"10%"
CDS_LIB"pure_quanta"
PART_NUMBER"CH4102K6E00";
"B"
$PN"2"9;
"A"
$PN"1"1;
%"Q_CAP"
"1","(-2625,1425)","0","pure_quanta","I36";
;
LOCATION"C791"
$SEC"1"
CDS_SEC"1"
VALUE"0.1UF"
PACK_TYPE"C0201"
VOLTAGE"10V"
TOLERANCE"10%"
MATERIAL"X7S"
CDS_LIB"pure_quanta"
PART_NUMBER"CH4102K6E00";
"B"
$PN"2"12;
"A"
$PN"1"11;
%"UNIVERSAL_GND"
"1","(-2175,1100)","0","pure_quanta_power","I38";
;
CDS_LIB"pure_quanta_power"
HDL_POWER"GND";
"A"12;
%"Q_CAP"
"1","(-2075,1425)","0","pure_quanta","I39";
;
LOCATION"C794"
$SEC"1"
CDS_SEC"1"
VALUE"0.1UF"
TOLERANCE"10%"
VOLTAGE"10V"
PACK_TYPE"C0201"
MATERIAL"X7S"
CDS_LIB"pure_quanta"
PART_NUMBER"CH4102K6E00";
"B"
$PN"2"12;
"A"
$PN"1"11;
%"Q_RES"
"1","(-7550,3850)","0","pure_quanta","I4";
;
LOCATION"R1046"
SEC"1"
TOLERANCE"5%"
PACK_TYPE"0402LF"
VALUE"0"
MATERIAL"EMPTY"
WATTAGE"1/16W"
CDS_LIB"pure_quanta"
SEC_TYPE"0402LF"
PART_NUMBER"CS00002JB13";
"B"
$PN"2"5;
"A"
$PN"1"10;
%"Q_CAP"
"1","(-2525,2525)","0","pure_quanta","I40";
;
LOCATION"C790"
$SEC"1"
CDS_SEC"1"
TOLERANCE"10%"
VALUE"0.1UF"
VOLTAGE"10V"
MATERIAL"X7S"
PACK_TYPE"C0201"
CDS_LIB"pure_quanta"
PART_NUMBER"CH4102K6E00";
"B"
$PN"2"9;
"A"
$PN"1"1;
%"Q_CAP"
"1","(-2275,2525)","0","pure_quanta","I41";
;
LOCATION"C987"
$SEC"1"
CDS_SEC"1"
PACK_TYPE"C0201"
TOLERANCE"10%"
MATERIAL"X7S"
VOLTAGE"10V"
VALUE"0.1UF"
CDS_LIB"pure_quanta"
PART_NUMBER"CH4102K6E00";
"B"
$PN"2"9;
"A"
$PN"1"1;
%"Q_CAP"
"1","(-2025,2525)","0","pure_quanta","I42";
;
LOCATION"C800"
$SEC"1"
CDS_SEC"1"
PACK_TYPE"C0201"
VOLTAGE"10V"
VALUE"0.1UF"
MATERIAL"X7S"
TOLERANCE"10%"
CDS_LIB"pure_quanta"
PART_NUMBER"CH4102K6E00";
"B"
$PN"2"9;
"A"
$PN"1"1;
%"Q_CAP"
"1","(-1750,2525)","0","pure_quanta","I43";
;
LOCATION"C784"
$SEC"1"
CDS_SEC"1"
VALUE"0.1UF"
VOLTAGE"10V"
MATERIAL"X7S"
PACK_TYPE"C0201"
TOLERANCE"10%"
CDS_LIB"pure_quanta"
PART_NUMBER"CH4102K6E00";
"B"
$PN"2"9;
"A"
$PN"1"1;
%"Q_CAP"
"1","(-3325,3225)","0","pure_quanta","I44";
;
LOCATION"C797"
$SEC"1"
CDS_SEC"1"
PACK_TYPE"0201"
TOLERANCE"20%"
MATERIAL"X6S"
VALUE"1UF"
VOLTAGE"4V"
CDS_LIB"pure_quanta"
PART_NUMBER"CH-10KMEE00";
"B"
$PN"2"2;
"A"
$PN"1"1;
%"Q_CAP"
"1","(-3100,3225)","0","pure_quanta","I45";
;
LOCATION"C781"
$SEC"1"
CDS_SEC"1"
TOLERANCE"20%"
VOLTAGE"4V"
VALUE"1UF"
PACK_TYPE"0201"
MATERIAL"X6S"
CDS_LIB"pure_quanta"
PART_NUMBER"CH-10KMEE00";
"B"
$PN"2"2;
"A"
$PN"1"1;
%"Q_CAP"
"1","(-2850,3225)","0","pure_quanta","I46";
;
LOCATION"C788"
$SEC"1"
CDS_SEC"1"
PACK_TYPE"0201"
TOLERANCE"20%"
VALUE"1UF"
VOLTAGE"4V"
MATERIAL"X6S"
CDS_LIB"pure_quanta"
PART_NUMBER"CH-10KMEE00";
"B"
$PN"2"2;
"A"
$PN"1"1;
%"Q_CAP"
"1","(-3325,3850)","0","pure_quanta","I47";
;
LOCATION"C796"
$SEC"1"
CDS_SEC"1"
MATERIAL"X6S"
VOLTAGE"6.3V"
TOLERANCE"20%"
PACK_TYPE"C0402"
VALUE"10UF"
CDS_LIB"pure_quanta"
PART_NUMBER"CH6101MEB01";
"B"
$PN"2"2;
"A"
$PN"1"1;
%"Q_CAP"
"1","(-3325,4475)","0","pure_quanta","I48";
;
LOCATION"C795"
$SEC"1"
CDS_SEC"1"
PACK_TYPE"C0805"
VOLTAGE"4V"
TOLERANCE"20%"
VALUE"100UF"
MATERIAL"X6S"
CDS_LIB"pure_quanta"
PART_NUMBER"CH710KMEA01";
"B"
$PN"2"2;
"A"
$PN"1"1;
%"Q_CAP"
"1","(-2875,3850)","0","pure_quanta","I49";
;
LOCATION"C981"
$SEC"1"
CDS_SEC"1"
TOLERANCE"20%"
MATERIAL"X6S"
VOLTAGE"6.3V"
VALUE"4.7UF"
PACK_TYPE"0402"
CDS_LIB"pure_quanta"
PART_NUMBER"CH5471MEB01";
"B"
$PN"2"2;
"A"
$PN"1"1;
%"Q_RES"
"1","(-7550,4050)","0","pure_quanta","I5";
;
LOCATION"R1045"
SEC"1"
VALUE"0"
PACK_TYPE"0402LF"
TOLERANCE"5%"
WATTAGE"1/16W"
MATERIAL"EMPTY"
SEC_TYPE"0402LF"
CDS_LIB"pure_quanta"
PART_NUMBER"CS00002JB13";
"B"
$PN"2"5;
"A"
$PN"1"10;
%"Q_CAP"
"1","(-3100,4475)","0","pure_quanta","I50";
;
LOCATION"C798"
$SEC"1"
CDS_SEC"1"
TOLERANCE"20%"
PACK_TYPE"C0805"
VOLTAGE"4V"
MATERIAL"X6S"
VALUE"100UF"
CDS_LIB"pure_quanta"
PART_NUMBER"CH710KMEA01";
"B"
$PN"2"2;
"A"
$PN"1"1;
%"Q_CAP"
"1","(-2875,4475)","0","pure_quanta","I51";
;
LOCATION"C802"
$SEC"1"
CDS_SEC"1"
VALUE"100UF"
VOLTAGE"4V"
TOLERANCE"20%"
MATERIAL"X6S"
PACK_TYPE"C0805"
CDS_LIB"pure_quanta"
PART_NUMBER"CH710KMEA01";
"B"
$PN"2"2;
"A"
$PN"1"1;
%"Q_CAP"
"1","(-2625,3225)","0","pure_quanta","I52";
;
LOCATION"C792"
$SEC"1"
CDS_SEC"1"
VOLTAGE"4V"
MATERIAL"X6S"
VALUE"1UF"
TOLERANCE"20%"
PACK_TYPE"0201"
CDS_LIB"pure_quanta"
PART_NUMBER"CH-10KMEE00";
"B"
$PN"2"2;
"A"
$PN"1"1;
%"Q_CAP"
"1","(-2375,3200)","0","pure_quanta","I54";
;
LOCATION"C975"
$SEC"1"
CDS_SEC"1"
PACK_TYPE"0201"
MATERIAL"X6S"
VALUE"1UF"
VOLTAGE"4V"
TOLERANCE"20%"
CDS_LIB"pure_quanta"
PART_NUMBER"CH-10KMEE00";
"B"
$PN"2"2;
"A"
$PN"1"1;
%"Q_CAP"
"1","(-2100,3200)","0","pure_quanta","I55";
;
LOCATION"C979"
$SEC"1"
CDS_SEC"1"
VALUE"1UF"
TOLERANCE"20%"
MATERIAL"X6S"
PACK_TYPE"0201"
VOLTAGE"4V"
CDS_LIB"pure_quanta"
PART_NUMBER"CH-10KMEE00";
"B"
$PN"2"2;
"A"
$PN"1"1;
%"Q_CAP"
"1","(-2650,3850)","0","pure_quanta","I56";
;
LOCATION"C967"
$SEC"1"
CDS_SEC"1"
VALUE"4.7UF"
MATERIAL"X6S"
PACK_TYPE"0402"
TOLERANCE"20%"
VOLTAGE"6.3V"
CDS_LIB"pure_quanta"
PART_NUMBER"CH5471MEB01";
"B"
$PN"2"2;
"A"
$PN"1"1;
%"Q_CAP"
"1","(-2400,3850)","0","pure_quanta","I57";
;
LOCATION"C970"
$SEC"1"
CDS_SEC"1"
MATERIAL"X6S"
TOLERANCE"20%"
VOLTAGE"6.3V"
PACK_TYPE"0402"
VALUE"4.7UF"
CDS_LIB"pure_quanta"
PART_NUMBER"CH5471MEB01";
"B"
$PN"2"2;
"A"
$PN"1"1;
%"Q_CAP"
"1","(-2650,4475)","0","pure_quanta","I58";
;
LOCATION"C966"
$SEC"1"
CDS_SEC"1"
PACK_TYPE"C0805"
TOLERANCE"20%"
VALUE"100UF"
MATERIAL"X6S"
VOLTAGE"4V"
CDS_LIB"pure_quanta"
PART_NUMBER"CH710KMEA01";
"B"
$PN"2"2;
"A"
$PN"1"1;
%"Q_CAP"
"1","(-2400,4475)","0","pure_quanta","I59";
;
LOCATION"C969"
$SEC"1"
CDS_SEC"1"
VOLTAGE"4V"
PACK_TYPE"C0402"
TOLERANCE"20%"
MATERIAL"X6S"
VALUE"22UF"
CDS_LIB"pure_quanta"
PART_NUMBER"CH622KMEB02";
"B"
$PN"2"2;
"A"
$PN"1"1;
%"Q_CAP"
"1","(-7050,4475)","0","pure_quanta","I6";
;
LOCATION"C666"
$SEC"1"
CDS_SEC"1"
TOLERANCE"20%"
MATERIAL"X6S"
PACK_TYPE"C0805"
VALUE"100UF"
VOLTAGE"4V"
CDS_LIB"pure_quanta"
PART_NUMBER"CH710KMEA01";
"B"
$PN"2"6;
"A"
$PN"1"5;
%"Q_CAP"
"1","(-2175,3850)","0","pure_quanta","I60";
;
LOCATION"C977"
$SEC"1"
CDS_SEC"1"
VALUE"4.7UF"
VOLTAGE"6.3V"
TOLERANCE"20%"
MATERIAL"X6S"
PACK_TYPE"0402"
CDS_LIB"pure_quanta"
PART_NUMBER"CH5471MEB01";
"B"
$PN"2"2;
"A"
$PN"1"1;
%"Q_CAP"
"1","(-1950,3850)","0","pure_quanta","I61";
;
LOCATION"C978"
$SEC"1"
CDS_SEC"1"
VOLTAGE"4V"
VALUE"1UF"
MATERIAL"X6S"
TOLERANCE"20%"
PACK_TYPE"0201"
CDS_LIB"pure_quanta"
PART_NUMBER"CH-10KMEE00";
"B"
$PN"2"2;
"A"
$PN"1"1;
%"Q_CAP"
"1","(-1725,3850)","0","pure_quanta","I62";
;
LOCATION"C783"
$SEC"1"
CDS_SEC"1"
PACK_TYPE"0201"
TOLERANCE"20%"
MATERIAL"X6S"
VOLTAGE"4V"
VALUE"1UF"
CDS_LIB"pure_quanta"
PART_NUMBER"CH-10KMEE00";
"B"
$PN"2"2;
"A"
$PN"1"1;
%"Q_CAP"
"1","(-2175,4475)","0","pure_quanta","I63";
;
LOCATION"C988"
$SEC"1"
CDS_SEC"1"
VALUE"22UF"
VOLTAGE"4V"
TOLERANCE"20%"
MATERIAL"X6S"
PACK_TYPE"C0402"
CDS_LIB"pure_quanta"
PART_NUMBER"CH622KMEB02";
"B"
$PN"2"2;
"A"
$PN"1"1;
%"Q_CAP"
"1","(-1950,4475)","0","pure_quanta","I64";
;
LOCATION"C974"
$SEC"1"
CDS_SEC"1"
VALUE"22UF"
VOLTAGE"4V"
TOLERANCE"20%"
PACK_TYPE"C0402"
MATERIAL"X6S"
CDS_LIB"pure_quanta"
PART_NUMBER"CH622KMEB02";
"B"
$PN"2"2;
"A"
$PN"1"1;
%"Q_CAP"
"1","(-1725,4475)","0","pure_quanta","I65";
;
LOCATION"C799"
$SEC"1"
CDS_SEC"1"
MATERIAL"X6S"
PACK_TYPE"C0402"
VOLTAGE"4V"
VALUE"22UF"
TOLERANCE"20%"
CDS_LIB"pure_quanta"
PART_NUMBER"CH622KMEB02";
"B"
$PN"2"2;
"A"
$PN"1"1;
%"Q_CAP"
"1","(-1825,3200)","0","pure_quanta","I66";
;
LOCATION"C983"
$SEC"1"
CDS_SEC"1"
VOLTAGE"4V"
TOLERANCE"20%"
PACK_TYPE"0201"
MATERIAL"X6S"
VALUE"1UF"
CDS_LIB"pure_quanta"
PART_NUMBER"CH-10KMEE00";
"B"
$PN"2"2;
"A"
$PN"1"1;
%"UNIVERSAL_GND"
"1","(-1225,2100)","0","pure_quanta_power","I67";
;
CDS_LIB"pure_quanta_power"
HDL_POWER"GND";
"A"9;
%"Q_CAP"
"1","(-1475,2525)","0","pure_quanta","I68";
;
LOCATION"C804"
$SEC"1"
CDS_SEC"1"
PACK_TYPE"C0201"
MATERIAL"X7S"
VOLTAGE"10V"
TOLERANCE"10%"
VALUE"0.1UF"
CDS_LIB"pure_quanta"
PART_NUMBER"CH4102K6E00";
"B"
$PN"2"9;
"A"
$PN"1"1;
%"Q_CAP"
"1","(-1225,2525)","0","pure_quanta","I69";
;
LOCATION"C968"
$SEC"1"
CDS_SEC"1"
TOLERANCE"10%"
VOLTAGE"10V"
MATERIAL"X7S"
PACK_TYPE"C0201"
VALUE"0.1UF"
CDS_LIB"pure_quanta"
PART_NUMBER"CH4102K6E00";
"B"
$PN"2"9;
"A"
$PN"1"1;
%"Q_CAP"
"1","(-6825,4475)","0","pure_quanta","I7";
;
LOCATION"C668"
$SEC"1"
CDS_SEC"1"
PACK_TYPE"C0402"
MATERIAL"X6S"
TOLERANCE"20%"
VOLTAGE"4V"
VALUE"22UF"
CDS_LIB"pure_quanta"
PART_NUMBER"CH622KMEB02";
"B"
$PN"2"6;
"A"
$PN"1"5;
%"UNIVERSAL_GND"
"1","(-725,2800)","0","pure_quanta_power","I71";
;
CDS_LIB"pure_quanta_power"
HDL_POWER"GND";
"A"2;
%"Q_CAP"
"1","(-1500,3850)","0","pure_quanta","I72";
;
LOCATION"C786"
$SEC"1"
CDS_SEC"1"
PACK_TYPE"0201"
VOLTAGE"4V"
VALUE"1UF"
MATERIAL"X6S"
TOLERANCE"20%"
CDS_LIB"pure_quanta"
PART_NUMBER"CH-10KMEE00";
"B"
$PN"2"2;
"A"
$PN"1"1;
%"Q_CAP"
"1","(-1250,3850)","0","pure_quanta","I73";
;
LOCATION"C779"
$SEC"1"
CDS_SEC"1"
VOLTAGE"4V"
PACK_TYPE"0201"
VALUE"1UF"
MATERIAL"X6S"
TOLERANCE"20%"
CDS_LIB"pure_quanta"
PART_NUMBER"CH-10KMEE00";
"B"
$PN"2"2;
"A"
$PN"1"1;
%"Q_CAP"
"1","(-1425,4475)","0","pure_quanta","I74";
;
LOCATION"C986"
$SEC"1"
CDS_SEC"1"
VOLTAGE"6.3V"
PACK_TYPE"C0402"
MATERIAL"X6S"
VALUE"10UF"
TOLERANCE"20%"
CDS_LIB"pure_quanta"
PART_NUMBER"CH6101MEB01";
"B"
$PN"2"2;
"A"
$PN"1"1;
%"Q_CAP"
"1","(-1125,4475)","0","pure_quanta","I75";
;
LOCATION"C973"
$SEC"1"
CDS_SEC"1"
PACK_TYPE"C0402"
TOLERANCE"20%"
MATERIAL"X6S"
VOLTAGE"6.3V"
VALUE"10UF"
CDS_LIB"pure_quanta"
PART_NUMBER"CH6101MEB01";
"B"
$PN"2"2;
"A"
$PN"1"1;
%"VCC_CORE"
"1","(-3325,5125)","0","pure_quanta_power","I76";
;
HDL_POWER"P0V9_CPU0_RT2_2A"
CDS_LIB"pure_quanta_power";
"A"1;
%"Q_CAP"
"1","(-3275,5750)","0","pure_quanta","I77";
;
LOCATION"C801"
$SEC"1"
CDS_SEC"1"
MATERIAL"X6S"
PACK_TYPE"C0805"
TOLERANCE"20%"
VOLTAGE"4V"
VALUE"100UF"
CDS_LIB"pure_quanta"
PART_NUMBER"CH710KMEA01";
"B"
$PN"2"8;
"A"
$PN"1"7;
%"Q_CAP"
"1","(-3000,5750)","0","pure_quanta","I78";
;
LOCATION"C805"
$SEC"1"
CDS_SEC"1"
VOLTAGE"4V"
PACK_TYPE"C0402"
MATERIAL"X6S"
TOLERANCE"20%"
VALUE"22UF"
CDS_LIB"pure_quanta"
PART_NUMBER"CH622KMEB02";
"B"
$PN"2"8;
"A"
$PN"1"7;
%"Q_CAP"
"1","(-2675,5725)","0","pure_quanta","I79";
;
LOCATION"C971"
$SEC"1"
CDS_SEC"1"
VALUE"10UF"
VOLTAGE"6.3V"
TOLERANCE"20%"
MATERIAL"X6S"
PACK_TYPE"C0402"
CDS_LIB"pure_quanta"
PART_NUMBER"CH6101MEB01";
"B"
$PN"2"8;
"A"
$PN"1"7;
%"UNIVERSAL_GND"
"1","(-6350,2975)","0","pure_quanta_power","I8";
;
CDS_LIB"pure_quanta_power"
HDL_POWER"GND";
"A"13;
%"Q_CAP"
"1","(-2375,5725)","0","pure_quanta","I80";
;
LOCATION"C976"
$SEC"1"
CDS_SEC"1"
VOLTAGE"6.3V"
VALUE"4.7UF"
MATERIAL"X6S"
TOLERANCE"20%"
PACK_TYPE"0402"
CDS_LIB"pure_quanta"
PART_NUMBER"CH5471MEB01";
"B"
$PN"2"8;
"A"
$PN"1"7;
%"Q_CAP"
"1","(-2075,5725)","0","pure_quanta","I81";
;
LOCATION"C980"
$SEC"1"
CDS_SEC"1"
TOLERANCE"20%"
VALUE"1UF"
MATERIAL"X6S"
VOLTAGE"4V"
PACK_TYPE"0201"
CDS_LIB"pure_quanta"
PART_NUMBER"CH-10KMEE00";
"B"
$PN"2"8;
"A"
$PN"1"7;
%"Q_CAP"
"1","(-1775,5700)","0","pure_quanta","I82";
;
LOCATION"C780"
$SEC"1"
CDS_SEC"1"
VOLTAGE"10V"
MATERIAL"X7S"
TOLERANCE"10%"
VALUE"0.1UF"
PACK_TYPE"C0201"
CDS_LIB"pure_quanta"
PART_NUMBER"CH4102K6E00";
"B"
$PN"2"8;
"A"
$PN"1"7;
%"Q_CAP"
"1","(-1500,5700)","0","pure_quanta","I83";
;
LOCATION"C782"
$SEC"1"
CDS_SEC"1"
TOLERANCE"10%"
PACK_TYPE"C0201"
VALUE"0.1UF"
VOLTAGE"10V"
MATERIAL"X7S"
CDS_LIB"pure_quanta"
PART_NUMBER"CH4102K6E00";
"B"
$PN"2"8;
"A"
$PN"1"7;
%"Q_CAP"
"1","(-1250,5700)","0","pure_quanta","I84";
;
LOCATION"C785"
$SEC"1"
CDS_SEC"1"
TOLERANCE"10%"
VALUE"0.1UF"
VOLTAGE"10V"
MATERIAL"X7S"
PACK_TYPE"C0201"
CDS_LIB"pure_quanta"
PART_NUMBER"CH4102K6E00";
"B"
$PN"2"8;
"A"
$PN"1"7;
%"UNIVERSAL_GND"
"1","(-1050,5300)","0","pure_quanta_power","I85";
;
CDS_LIB"pure_quanta_power"
HDL_POWER"GND";
"A"8;
%"Q_CAP"
"1","(-975,5700)","0","pure_quanta","I86";
;
LOCATION"C789"
$SEC"1"
CDS_SEC"1"
PACK_TYPE"C0201"
MATERIAL"X7S"
VALUE"0.1UF"
VOLTAGE"10V"
TOLERANCE"10%"
CDS_LIB"pure_quanta"
PART_NUMBER"CH4102K6E00";
"B"
$PN"2"8;
"A"
$PN"1"7;
%"Q_CAP"
"1","(-3100,3850)","0","pure_quanta","I87";
;
LOCATION"C803"
$SEC"1"
CDS_SEC"1"
VALUE"10UF"
MATERIAL"X6S"
VOLTAGE"6.3V"
TOLERANCE"20%"
PACK_TYPE"C0402"
CDS_LIB"pure_quanta"
PART_NUMBER"CH6101MEB01";
"B"
$PN"2"2;
"A"
$PN"1"1;
%"Q_INDUCTOR"
"1","(-8075,4400)","3","pure_quanta","I88";
;
LOCATION"L29"
$SEC"1"
CDS_SEC"1"
PACK_TYPE"SMLF"
MATERIAL"IND"
VALUE"BLM15PD121SN1D/1300MA"
CDS_LIB"pure_quanta"
NEEDS_NO_SIZE"TRUE"
PART_NUMBER"CX5PD121000";
"1"
$PN"1"3;
"2"
$PN"2"10;
%"Q_RES"
"2","(-7950,4375)","0","pure_quanta","I89";
;
LOCATION"R1050"
$SEC"1"
CDS_SEC"1"
PACK_TYPE"0402LF"
MATERIAL"EMPTY"
TOLERANCE"5%"
VALUE"0"
WATTAGE"1/16W"
CDS_LIB"pure_quanta"
PART_NUMBER"CS00002JB13";
"A"
$PN"1"3;
"B"
$PN"2"10;
%"Q_CAP"
"1","(-6625,3400)","0","pure_quanta","I9";
;
LOCATION"C676"
$SEC"1"
CDS_SEC"1"
VALUE"1UF"
PACK_TYPE"0201"
MATERIAL"X6S"
TOLERANCE"20%"
VOLTAGE"4V"
CDS_LIB"pure_quanta"
PART_NUMBER"CH-10KMEE00";
"B"
$PN"2"13;
"A"
$PN"1"10;
%"Q_CAP"
"1","(-2875,1425)","0","pure_quanta","I90";
;
LOCATION"C787"
$SEC"1"
CDS_SEC"1"
VALUE"1UF"
MATERIAL"X6S"
VOLTAGE"4V"
PACK_TYPE"0201"
TOLERANCE"20%"
CDS_LIB"pure_quanta"
PART_NUMBER"CH-10KMEE00";
"B"
$PN"2"12;
"A"
$PN"1"11;
%"Q_CAP"
"1","(-2325,1425)","0","pure_quanta","I91";
;
LOCATION"C793"
$SEC"1"
CDS_SEC"1"
MATERIAL"X6S"
VALUE"1UF"
PACK_TYPE"0201"
VOLTAGE"4V"
TOLERANCE"20%"
CDS_LIB"pure_quanta"
PART_NUMBER"CH-10KMEE00";
"B"
$PN"2"12;
"A"
$PN"1"11;
%"Q_CAP"
"1","(-1575,3200)","0","pure_quanta","I92";
;
LOCATION"C972"
$SEC"1"
CDS_SEC"1"
MATERIAL"X7S"
TOLERANCE"10%"
VOLTAGE"10V"
VALUE"0.1UF"
PACK_TYPE"C0201"
CDS_LIB"pure_quanta"
PART_NUMBER"CH4102K6E00";
"B"
$PN"2"2;
"A"
$PN"1"1;
%"Q_CAP"
"1","(-1325,3200)","0","pure_quanta","I93";
;
LOCATION"C985"
$SEC"1"
CDS_SEC"1"
PACK_TYPE"C0201"
MATERIAL"X7S"
TOLERANCE"10%"
VOLTAGE"10V"
VALUE"0.1UF"
CDS_LIB"pure_quanta"
PART_NUMBER"CH4102K6E00";
"B"
$PN"2"2;
"A"
$PN"1"1;
%"Q_CAPP"
"1","(-975,2525)","0","pure_quanta","I94";
;
LOCATION"C7014"
$SEC"1"
CDS_SEC"1"
MATERIAL"SPCAP"
VOLTAGE"2.5V"
PACK_TYPE"SMLF"
TOLERANCE"20%"
VALUE"470UF"
CDS_LIB"pure_quanta"
PART_NUMBER"CH747LM8818";
"A"
$PN"1"1;
"B"
$PN"2"9;
%"Q_CAPP"
"1","(-675,2525)","0","pure_quanta","I95";
;
LOCATION"C7015"
$SEC"1"
CDS_SEC"1"
VALUE"470UF"
TOLERANCE"20%"
MATERIAL"SPCAP"
PACK_TYPE"SMLF"
VOLTAGE"2.5V"
CDS_LIB"pure_quanta"
PART_NUMBER"CH747LM8818";
"A"
$PN"1"1;
"B"
$PN"2"9;
%"Q_CAP"
"1","(-375,2525)","0","pure_quanta","I96";
;
LOCATION"C7016"
$SEC"1"
CDS_SEC"1"
TOLERANCE"20%"
MATERIAL"X6S"
PACK_TYPE"C0805"
VALUE"100UF"
VOLTAGE"4V"
CDS_LIB"pure_quanta"
PART_NUMBER"CH710KMEA01";
"B"
$PN"2"9;
"A"
$PN"1"1;
END.
